FILE_TYPE = CONNECTIVITY;
{Allegro Design Entry HDL 17.2-2016 S081 (4005846) 1/11/2022}
"PAGE_NUMBER" = 16;
0"NC";
1"PGPPA_BMC_AUX\g";
2"P3V3_RTC_AUX\g";
3"P3V3_P1V8_I2C_I3C\g";
4"P1V0_AUX\g";
5"P1V8_AUX\g";
6"P3V3_AUX\g";
7"P3V3_RGM\g";
8"P1V8_AUX\g";
9"P1V2_AUX\g";
10"P1V2_AUX\g";
11"P1V2_AUX\g";
12"P1V0_AUX\g";
13"P1V8_AUX\g";
14"P3V3_P1V8_SD2VDD\g";
15"P3V3_P2V5_P1V8_RVDD\g";
16"P3V3_P1V8_SD1VDD\g";
17"P1V2_P1V0_I3C_VDDL2\g";
18"P1V2_P1V0_I3C_VDDL1\g";
19"P3V3_AUX\g";
20"GND\g";
21"GND\g";
22"GND\g";
23"GND\g";
24"GND\g";
25"GND\g";
26"GND\g";
27"GND\g";
28"GND\g";
29"GND\g";
30"GND\g";
31"GND\g";
32"GND\g";
33"A_BMC_ADCREXT1";
34"ADCVREFEXT1";
35"A_BMC_DACREST";
36"P1V0_STBY_PLAVDD";
37"P1V8_STBY_PE_VCC18A";
38"P1V8_STBY_RC_VCC18A";
39"P1V0_STBY_DP_VCC10A";
40"P1V8_STBY_DP_VCC18A";
41"P1V2_STBY_MVDD_CK";
42"A_BMC_ADCREXT0";
43"P3V3_STBY_DACAV33";
44"A_BMC_ADCAV33";
45"ADCVREFEXT0";
46"P1V0_STBY_RC_VCC10A";
47"P1V0_STBY_PE_VCC10A";
48"P1V8_STBY_AVDDPLL";
49"A_BMC_ADCVREFN1";
50"A_BMC_ADCVREFP1";
51"P3V3_STBY_PLLAHVDD";
52"A_BMC_ADCVREFP0";
53"A_BMC_ADCVREFN0";
%"Q_CAP"
"1","(-425,4425)","0","pure_quanta","I100";
;
PACK_TYPE"0402"
VALUE"0.1UF"
TOLERANCE"10%"
MATERIAL"X7R"
VOLTAGE"25V"
PART_NUMBER"CH4104K1B00"
CDS_LIB"pure_quanta"
LOCATION"C77"
$SEC"1"
CDS_SEC"1";
"B"
$PN"2"32;
"A"
$PN"1"44;
%"UNIVERSAL_GND"
"1","(2625,-250)","0","logical_power","I105";
;
HDL_POWER"GND"
CDS_LIB"logical_power";
"A"20;
%"Q_CAP"
"1","(2625,-50)","0","pure_quanta","I106";
;
PACK_TYPE"0402"
TOLERANCE"10%"
MATERIAL"X7R"
PART_NUMBER"CH4104K1B00"
VOLTAGE"25V"
VALUE"0.1UF"
CDS_LIB"pure_quanta"
LOCATION"C83"
$SEC"1"
CDS_SEC"1";
"B"
$PN"2"20;
"A"
$PN"1"2;
%"UNIVERSAL_POWER"
"1","(2850,175)","0","logical_power","I107";
;
HDL_POWER"P3V3_RTC_AUX"
CDS_LIB"logical_power";
"A"2;
%"Q_CAP"
"1","(2850,725)","0","pure_quanta","I118";
;
PACK_TYPE"0402"
VALUE"0.1UF"
TOLERANCE"10%"
MATERIAL"X7R"
PART_NUMBER"CH4104K1B00"
VOLTAGE"25V"
CDS_LIB"pure_quanta"
$LOCATION"C89"
CDS_LOCATION"C89"
$SEC"1"
CDS_SEC"1";
"B"
$PN"2"26;
"A"
$PN"1"8;
%"Q_CAP"
"1","(3050,725)","0","pure_quanta","I119";
;
PACK_TYPE"0402"
TOLERANCE"10%"
MATERIAL"X7R"
VOLTAGE"25V"
VALUE"0.1UF"
PART_NUMBER"CH4104K1B00"
CDS_LIB"pure_quanta"
LOCATION"C95"
$SEC"1"
CDS_SEC"1";
"B"
$PN"2"26;
"A"
$PN"1"8;
%"Q_CAP"
"1","(2775,1275)","0","pure_quanta","I120";
;
PACK_TYPE"0402"
TOLERANCE"10%"
MATERIAL"X7R"
VOLTAGE"25V"
VALUE"0.1UF"
PART_NUMBER"CH4104K1B00"
CDS_LIB"pure_quanta"
LOCATION"C85"
$SEC"1"
CDS_SEC"1";
"B"
$PN"2"21;
"A"
$PN"1"7;
%"UNIVERSAL_GND"
"1","(2775,1000)","0","logical_power","I121";
;
HDL_POWER"GND"
CDS_LIB"logical_power";
"A"21;
%"UNIVERSAL_POWER"
"1","(2775,1550)","0","logical_power","I122";
;
HDL_POWER"P3V3_RGM"
CDS_LIB"logical_power";
"A"7;
%"Q_CAP"
"1","(2825,1875)","0","pure_quanta","I123";
;
PACK_TYPE"0402"
VALUE"0.1UF"
TOLERANCE"10%"
MATERIAL"X7R"
PART_NUMBER"CH4104K1B00"
VOLTAGE"25V"
CDS_LIB"pure_quanta"
LOCATION"C88"
$SEC"1"
CDS_SEC"1";
"B"
$PN"2"22;
"A"
$PN"1"6;
%"Q_CAP"
"1","(3025,1875)","0","pure_quanta","I124";
;
PACK_TYPE"0402"
VALUE"0.1UF"
TOLERANCE"10%"
MATERIAL"X7R"
VOLTAGE"25V"
PART_NUMBER"CH4104K1B00"
CDS_LIB"pure_quanta"
LOCATION"C94"
$SEC"1"
CDS_SEC"1";
"B"
$PN"2"22;
"A"
$PN"1"6;
%"UNIVERSAL_POWER"
"1","(3200,375)","0","logical_power","I125";
;
HDL_POWER"PGPPA_BMC_AUX"
CDS_LIB"logical_power";
"A"1;
%"Q_CAP"
"1","(3250,725)","0","pure_quanta","I126";
;
VALUE"0.1UF"
VOLTAGE"25V"
PACK_TYPE"0402"
MATERIAL"X7R"
TOLERANCE"10%"
PART_NUMBER"CH4104K1B00"
CDS_LIB"pure_quanta"
LOCATION"C102"
$SEC"1"
CDS_SEC"1";
"B"
$PN"2"26;
"A"
$PN"1"8;
%"Q_CAP"
"1","(3425,725)","0","pure_quanta","I127";
;
PACK_TYPE"C0402"
TOLERANCE"10%"
MATERIAL"X6S"
VALUE"1UF"
VOLTAGE"25V"
PART_NUMBER"CH5104KEB02"
CDS_LIB"pure_quanta"
LOCATION"C106"
$SEC"1"
CDS_SEC"1";
"B"
$PN"2"26;
"A"
$PN"1"8;
%"Q_CAP"
"1","(3600,725)","0","pure_quanta","I128";
;
PACK_TYPE"C0402"
TOLERANCE"10%"
MATERIAL"X6S"
PART_NUMBER"CH5104KEB02"
VALUE"1UF"
VOLTAGE"25V"
CDS_LIB"pure_quanta"
LOCATION"C111"
$SEC"1"
CDS_SEC"1";
"B"
$PN"2"26;
"A"
$PN"1"8;
%"Q_CAP"
"1","(3775,725)","0","pure_quanta","I129";
;
PACK_TYPE"C0402"
TOLERANCE"10%"
MATERIAL"X6S"
VALUE"1UF"
VOLTAGE"25V"
PART_NUMBER"CH5104KEB02"
CDS_LIB"pure_quanta"
LOCATION"C116"
$SEC"1"
CDS_SEC"1";
"B"
$PN"2"26;
"A"
$PN"1"8;
%"Q_CAP"
"1","(3975,725)","0","pure_quanta","I131";
;
TOLERANCE"20%"
MATERIAL"X6S"
VALUE"22UF"
PACK_TYPE"C0603"
VOLTAGE"6.3V"
PART_NUMBER"CH6221ME900"
CDS_LIB"pure_quanta"
LOCATION"C121"
$SEC"1"
CDS_SEC"1";
"B"
$PN"2"26;
"A"
$PN"1"8;
%"Q_CAP"
"1","(3225,1875)","0","pure_quanta","I132";
;
PACK_TYPE"0402"
MATERIAL"X7R"
TOLERANCE"10%"
VOLTAGE"25V"
VALUE"0.1UF"
PART_NUMBER"CH4104K1B00"
CDS_LIB"pure_quanta"
LOCATION"C101"
$SEC"1"
CDS_SEC"1";
"B"
$PN"2"22;
"A"
$PN"1"6;
%"Q_CAP"
"1","(3575,1875)","0","pure_quanta","I133";
;
VALUE"1UF"
MATERIAL"X6S"
TOLERANCE"10%"
PART_NUMBER"CH5104KEB02"
PACK_TYPE"C0402"
VOLTAGE"25V"
CDS_LIB"pure_quanta"
LOCATION"C110"
$SEC"1"
CDS_SEC"1";
"B"
$PN"2"22;
"A"
$PN"1"6;
%"UNIVERSAL_GND"
"1","(4050,1600)","0","logical_power","I134";
;
HDL_POWER"GND"
CDS_LIB"logical_power";
"A"22;
%"Q_CAP"
"1","(3750,1875)","0","pure_quanta","I135";
;
VOLTAGE"25V"
VALUE"1UF"
TOLERANCE"10%"
PACK_TYPE"C0402"
MATERIAL"X6S"
PART_NUMBER"CH5104KEB02"
CDS_LIB"pure_quanta"
LOCATION"C115"
$SEC"1"
CDS_SEC"1";
"B"
$PN"2"22;
"A"
$PN"1"6;
%"UNIVERSAL_GND"
"1","(4050,2225)","0","logical_power","I137";
;
HDL_POWER"GND"
CDS_LIB"logical_power";
"A"23;
%"Q_CAP"
"1","(4175,725)","0","pure_quanta","I143";
;
TOLERANCE"20%"
MATERIAL"X6S"
PART_NUMBER"CH6221ME900"
VALUE"22UF"
PACK_TYPE"C0603"
VOLTAGE"6.3V"
CDS_LIB"pure_quanta"
LOCATION"C126"
$SEC"1"
CDS_SEC"1";
"B"
$PN"2"26;
"A"
$PN"1"8;
%"UNIVERSAL_POWER"
"1","(4275,975)","0","logical_power","I144";
;
HDL_POWER"P1V8_AUX"
CDS_LIB"logical_power";
"A"8;
%"UNIVERSAL_POWER"
"1","(4250,2125)","0","logical_power","I146";
;
HDL_POWER"P3V3_AUX"
CDS_LIB"logical_power";
"A"6;
%"Q_CAP"
"1","(2825,2500)","0","pure_quanta","I147";
;
VALUE"0.1UF"
TOLERANCE"10%"
MATERIAL"X7R"
PART_NUMBER"CH4104K1B00"
VOLTAGE"25V"
PACK_TYPE"0402"
CDS_LIB"pure_quanta"
LOCATION"C87"
$SEC"1"
CDS_SEC"1";
"B"
$PN"2"23;
"A"
$PN"1"5;
%"Q_CAP"
"1","(3025,2500)","0","pure_quanta","I148";
;
PACK_TYPE"0402"
VALUE"0.1UF"
TOLERANCE"10%"
MATERIAL"X7R"
VOLTAGE"25V"
PART_NUMBER"CH4104K1B00"
CDS_LIB"pure_quanta"
LOCATION"C93"
$SEC"1"
CDS_SEC"1";
"B"
$PN"2"23;
"A"
$PN"1"5;
%"Q_CAP"
"1","(2825,3200)","0","pure_quanta","I149";
;
VALUE"0.1UF"
TOLERANCE"10%"
MATERIAL"X7R"
PART_NUMBER"CH4104K1B00"
VOLTAGE"25V"
PACK_TYPE"0402"
CDS_LIB"pure_quanta"
LOCATION"C86"
$SEC"1"
CDS_SEC"1";
"B"
$PN"2"24;
"A"
$PN"1"4;
%"Q_CAP"
"1","(3025,3200)","0","pure_quanta","I150";
;
TOLERANCE"10%"
VOLTAGE"25V"
MATERIAL"X7R"
PACK_TYPE"0402"
VALUE"0.1UF"
PART_NUMBER"CH4104K1B00"
CDS_LIB"pure_quanta"
LOCATION"C92"
$SEC"1"
CDS_SEC"1";
"B"
$PN"2"24;
"A"
$PN"1"4;
%"Q_CAP"
"1","(2950,3825)","0","pure_quanta","I151";
;
VOLTAGE"25V"
VALUE"0.1UF"
PACK_TYPE"0402"
TOLERANCE"10%"
MATERIAL"X7R"
PART_NUMBER"CH4104K1B00"
CDS_LIB"pure_quanta"
LOCATION"C91"
$SEC"1"
CDS_SEC"1";
"B"
$PN"2"25;
"A"
$PN"1"9;
%"Q_CAP"
"1","(3225,2500)","0","pure_quanta","I152";
;
VALUE"0.1UF"
PACK_TYPE"0402"
MATERIAL"X7R"
TOLERANCE"10%"
VOLTAGE"25V"
PART_NUMBER"CH4104K1B00"
CDS_LIB"pure_quanta"
LOCATION"C100"
$SEC"1"
CDS_SEC"1";
"B"
$PN"2"23;
"A"
$PN"1"5;
%"Q_CAP"
"1","(3400,2500)","0","pure_quanta","I153";
;
PACK_TYPE"0402"
VALUE"0.1UF"
TOLERANCE"10%"
MATERIAL"X7R"
VOLTAGE"25V"
PART_NUMBER"CH4104K1B00"
CDS_LIB"pure_quanta"
LOCATION"C105"
$SEC"1"
CDS_SEC"1";
"B"
$PN"2"23;
"A"
$PN"1"5;
%"Q_CAP"
"1","(3225,3200)","0","pure_quanta","I154";
;
VALUE"0.1UF"
TOLERANCE"10%"
VOLTAGE"25V"
MATERIAL"X7R"
PACK_TYPE"0402"
PART_NUMBER"CH4104K1B00"
CDS_LIB"pure_quanta"
LOCATION"C99"
$SEC"1"
CDS_SEC"1";
"B"
$PN"2"24;
"A"
$PN"1"4;
%"Q_CAP"
"1","(3400,3200)","0","pure_quanta","I155";
;
PACK_TYPE"C0402"
MATERIAL"X6S"
VALUE"1UF"
VOLTAGE"25V"
TOLERANCE"10%"
PART_NUMBER"CH5104KEB02"
CDS_LIB"pure_quanta"
LOCATION"C104"
$SEC"1"
CDS_SEC"1";
"B"
$PN"2"24;
"A"
$PN"1"4;
%"Q_CAP"
"1","(3575,2500)","0","pure_quanta","I156";
;
PACK_TYPE"0402"
TOLERANCE"10%"
MATERIAL"X7R"
VOLTAGE"25V"
VALUE"0.1UF"
PART_NUMBER"CH4104K1B00"
CDS_LIB"pure_quanta"
LOCATION"C109"
$SEC"1"
CDS_SEC"1";
"B"
$PN"2"23;
"A"
$PN"1"5;
%"Q_CAP"
"1","(3575,3200)","0","pure_quanta","I157";
;
MATERIAL"X6S"
VALUE"1UF"
TOLERANCE"10%"
VOLTAGE"25V"
PACK_TYPE"C0402"
PART_NUMBER"CH5104KEB02"
CDS_LIB"pure_quanta"
LOCATION"C108"
$SEC"1"
CDS_SEC"1";
"B"
$PN"2"24;
"A"
$PN"1"4;
%"Q_CAP"
"1","(3750,2500)","0","pure_quanta","I158";
;
PACK_TYPE"C0402"
TOLERANCE"10%"
MATERIAL"X6S"
PART_NUMBER"CH5104KEB02"
VOLTAGE"25V"
VALUE"1UF"
CDS_LIB"pure_quanta"
LOCATION"C114"
$SEC"1"
CDS_SEC"1";
"B"
$PN"2"23;
"A"
$PN"1"5;
%"Q_CAP"
"1","(3950,2500)","0","pure_quanta","I159";
;
VALUE"1UF"
VOLTAGE"25V"
MATERIAL"X6S"
TOLERANCE"10%"
PACK_TYPE"C0402"
PART_NUMBER"CH5104KEB02"
CDS_LIB"pure_quanta"
LOCATION"C119"
$SEC"1"
CDS_SEC"1";
"B"
$PN"2"23;
"A"
$PN"1"5;
%"UNIVERSAL_GND"
"1","(4050,2925)","0","logical_power","I161";
;
HDL_POWER"GND"
CDS_LIB"logical_power";
"A"24;
%"Q_CAP"
"1","(3950,3200)","0","pure_quanta","I162";
;
MATERIAL"X6S"
VALUE"22UF"
PACK_TYPE"C0603"
TOLERANCE"20%"
VOLTAGE"6.3V"
CDS_LIB"pure_quanta"
PART_NUMBER"CH6221ME900"
LOCATION"C118"
$SEC"1"
CDS_SEC"1";
"B"
$PN"2"24;
"A"
$PN"1"4;
%"Q_CAP"
"1","(3150,3825)","0","pure_quanta","I163";
;
PACK_TYPE"0402"
MATERIAL"X7R"
TOLERANCE"10%"
VOLTAGE"25V"
VALUE"0.1UF"
PART_NUMBER"CH4104K1B00"
CDS_LIB"pure_quanta"
LOCATION"C98"
$SEC"1"
CDS_SEC"1";
"B"
$PN"2"25;
"A"
$PN"1"9;
%"Q_CAP"
"1","(3325,3825)","0","pure_quanta","I164";
;
VOLTAGE"25V"
VALUE"0.1UF"
PACK_TYPE"0402"
TOLERANCE"10%"
MATERIAL"X7R"
PART_NUMBER"CH4104K1B00"
CDS_LIB"pure_quanta"
LOCATION"C103"
$SEC"1"
CDS_SEC"1";
"B"
$PN"2"25;
"A"
$PN"1"9;
%"Q_CAP"
"1","(3525,3825)","0","pure_quanta","I165";
;
VOLTAGE"25V"
VALUE"0.1UF"
TOLERANCE"10%"
MATERIAL"X7R"
PACK_TYPE"0402"
PART_NUMBER"CH4104K1B00"
CDS_LIB"pure_quanta"
LOCATION"C107"
$SEC"1"
CDS_SEC"1";
"B"
$PN"2"25;
"A"
$PN"1"9;
%"Q_CAP"
"1","(3725,3825)","0","pure_quanta","I166";
;
VALUE"0.1UF"
TOLERANCE"10%"
VOLTAGE"25V"
PACK_TYPE"0402"
MATERIAL"X7R"
PART_NUMBER"CH4104K1B00"
CDS_LIB"pure_quanta"
LOCATION"C112"
$SEC"1"
CDS_SEC"1";
"B"
$PN"2"25;
"A"
$PN"1"9;
%"Q_CAP"
"1","(3900,3825)","0","pure_quanta","I167";
;
PART_NUMBER"CH5104KEB02"
PACK_TYPE"C0402"
MATERIAL"X6S"
VALUE"1UF"
VOLTAGE"25V"
TOLERANCE"10%"
CDS_LIB"pure_quanta"
LOCATION"C117"
$SEC"1"
CDS_SEC"1";
"B"
$PN"2"25;
"A"
$PN"1"9;
%"Q_CAP"
"1","(4075,3825)","0","pure_quanta","I168";
;
PACK_TYPE"C0402"
MATERIAL"X6S"
VALUE"1UF"
VOLTAGE"25V"
TOLERANCE"10%"
PART_NUMBER"CH5104KEB02"
CDS_LIB"pure_quanta"
LOCATION"C122"
$SEC"1"
CDS_SEC"1";
"B"
$PN"2"25;
"A"
$PN"1"9;
%"Q_CAP"
"1","(4150,2500)","0","pure_quanta","I169";
;
TOLERANCE"20%"
MATERIAL"X6S"
VALUE"22UF"
VOLTAGE"6.3V"
PART_NUMBER"CH6221ME900"
PACK_TYPE"C0603"
CDS_LIB"pure_quanta"
LOCATION"C124"
$SEC"1"
CDS_SEC"1";
"B"
$PN"2"23;
"A"
$PN"1"5;
%"UNIVERSAL_POWER"
"1","(4250,2750)","0","logical_power","I170";
;
HDL_POWER"P1V8_AUX"
CDS_LIB"logical_power";
"A"5;
%"Q_CAP"
"1","(4150,3200)","0","pure_quanta","I171";
;
VALUE"22UF"
VOLTAGE"6.3V"
PACK_TYPE"C0603"
PART_NUMBER"CH6221ME900"
MATERIAL"X6S"
TOLERANCE"20%"
CDS_LIB"pure_quanta"
LOCATION"C123"
$SEC"1"
CDS_SEC"1";
"B"
$PN"2"24;
"A"
$PN"1"4;
%"UNIVERSAL_POWER"
"1","(4250,3450)","0","logical_power","I172";
;
HDL_POWER"P1V0_AUX"
CDS_LIB"logical_power";
"A"4;
%"Q_CAP"
"1","(4250,3825)","0","pure_quanta","I173";
;
VALUE"1UF"
VOLTAGE"25V"
MATERIAL"X6S"
TOLERANCE"10%"
PACK_TYPE"C0402"
PART_NUMBER"CH5104KEB02"
CDS_LIB"pure_quanta"
LOCATION"C127"
$SEC"1"
CDS_SEC"1";
"B"
$PN"2"25;
"A"
$PN"1"9;
%"Q_CAP"
"1","(4425,3825)","0","pure_quanta","I174";
;
VOLTAGE"25V"
VALUE"1UF"
PACK_TYPE"C0402"
TOLERANCE"10%"
MATERIAL"X6S"
PART_NUMBER"CH5104KEB02"
CDS_LIB"pure_quanta"
LOCATION"C129"
$SEC"1"
CDS_SEC"1";
"B"
$PN"2"25;
"A"
$PN"1"9;
%"UNIVERSAL_GND"
"1","(4725,3550)","0","logical_power","I175";
;
HDL_POWER"GND"
CDS_LIB"logical_power";
"A"25;
%"UNIVERSAL_POWER"
"1","(4925,4075)","0","logical_power","I178";
;
HDL_POWER"P1V2_AUX"
CDS_LIB"logical_power";
"A"9;
%"Q_CAP"
"1","(2775,3825)","0","pure_quanta","I179";
;
VOLTAGE"25V"
VALUE"0.1UF"
TOLERANCE"10%"
MATERIAL"X7R"
PACK_TYPE"0402"
PART_NUMBER"CH4104K1B00"
CDS_LIB"pure_quanta"
LOCATION"C84"
$SEC"1"
CDS_SEC"1";
"B"
$PN"2"25;
"A"
$PN"1"9;
%"Q_CAP"
"1","(2600,3825)","0","pure_quanta","I180";
;
TOLERANCE"10%"
VALUE"0.1UF"
MATERIAL"X7R"
VOLTAGE"25V"
PART_NUMBER"CH4104K1B00"
PACK_TYPE"0402"
CDS_LIB"pure_quanta"
LOCATION"C82"
$SEC"1"
CDS_SEC"1";
"B"
$PN"2"25;
"A"
$PN"1"9;
%"Q_CAP"
"1","(-775,1425)","0","pure_quanta","I183";
;
PACK_TYPE"0402"
VALUE"0.1UF"
TOLERANCE"10%"
MATERIAL"X7R"
PART_NUMBER"CH4104K1B00"
VOLTAGE"25V"
CDS_LIB"pure_quanta"
LOCATION"C76"
$SEC"1"
CDS_SEC"1";
"B"
$PN"2"29;
"A"
$PN"1"11;
%"UNIVERSAL_GND"
"1","(4075,450)","0","logical_power","I184";
;
HDL_POWER"GND"
CDS_LIB"logical_power";
"A"26;
%"Q_RES"
"1","(-1450,3250)","0","pure_quanta","I187";
;
WATTAGE"1/16W"
TOLERANCE"1%"
PART_NUMBER"CS22742FB05"
PACK_TYPE"0402LF"
MATERIAL"CHIP"
VALUE"2.74K"
CDS_LIB"pure_quanta"
LOCATION"R235"
$SEC"1"
CDS_SEC"1";
"B"
$PN"2"35;
"A"
$PN"1"31;
%"AST2600A3GP"
"5","(1125,2150)","0","pure_quanta","I188";
;
VALUE"AST2600A3-GP"
PART_TYPE"SMLF"
PART_NUMBER"AJ026000T06"
MATERIAL"IC"
CDS_LIB"pure_quanta"
CDS_LMAN_SYM_OUTLINE"-700,2000,700,-2000"
NEEDS_NO_SIZE"TRUE"
LOCATION"U5"
$SEC"5"
CDS_SEC"5";
"PV33D_RGM_K12"
$PN"K12"7;
"PV33D_RGM_K11"
$PN"K11"7;
"I3CVDDL2"
$PN"U21"17;
"I3CVDDL1"
$PN"V22"18;
"DPLLAVDD"
$PN"J9"36;
"PV33D_H15"
$PN"H15"6;
"I3CVDDH_F20"
$PN"F20"3;
"SD2VDD_H19"
$PN"H19"14;
"SD1VDD_H21"
$PN"H21"16;
"PV18D_R12"
$PN"R12"5;
"PV18D_P12"
$PN"P12"5;
"PV18D_N12"
$PN"N12"5;
"ADCVREFEXT1"
$PN"AF17"34;
"ADCVREFEXT0"
$PN"AF19"45;
"IV10D_R10"
$PN"R10"4;
"PV18D_RGM_J12"
$PN"J12"5;
"ADCAV33_AA21"
$PN"AA21"44;
"PV18D_SLI_W14"
$PN"W14"8;
"PV18D_SLI_W13"
$PN"W13"8;
"PV18D_SLI_V13"
$PN"V13"8;
"PV18D_SLI_U13"
$PN"U13"8;
"PV18D_SLI_T13"
$PN"T13"8;
"PV18D_SLI_R13"
$PN"R13"8;
"PV18D_SLI_P13"
$PN"P13"8;
"PV18D_SLI_N13"
$PN"N13"8;
"PV18D_SLI_M13"
$PN"M13"8;
"PV18D_SLI_L13"
$PN"L13"8;
"BATVDD"
$PN"V23"2;
"PV33D_T22"
$PN"T22"6;
"PV33D_R22"
$PN"R22"6;
"PV33D_P22"
$PN"P22"6;
"PV33D_N22"
$PN"N22"6;
"PV33D_W19"
$PN"W19"6;
"PV33D_W18"
$PN"W18"6;
"PV33D_W17"
$PN"W17"6;
"PV33D_W16"
$PN"W16"6;
"PV33D_H17"
$PN"H17"6;
"PV33D_H16"
$PN"H16"6;
"PV18D_RGM_H12"
$PN"H12"5;
"PV18D_J8"
$PN"J8"5;
"PV18D_H8"
$PN"H8"5;
"PV18D_V6"
$PN"V6"5;
"PV18D_U6"
$PN"U6"5;
"IV10D_R9"
$PN"R9"4;
"IV10D_P11"
$PN"P11"4;
"IV10D_N11"
$PN"N11"4;
"IV10D_M11"
$PN"M11"4;
"IV10D_P8"
$PN"P8"4;
"IV10D_N8"
$PN"N8"4;
"I3CVDDH_F19"
$PN"F19"3;
"LPVDD"
$PN"W15"1;
"SD2VDD_H18"
$PN"H18"14;
"SD1VDD_G21"
$PN"G21"16;
"RVDD_K21"
$PN"K21"15;
"RVDD_J21"
$PN"J21"15;
"RVDD_M22"
$PN"M22"15;
"RVDD_L22"
$PN"L22"15;
"IV12D_U18"
$PN"U18"9;
"IV12D_U17"
$PN"U17"9;
"IV12D_U16"
$PN"U16"9;
"IV12D_U15"
$PN"U15"9;
"IV12D_T21"
$PN"T21"9;
"IV12D_R21"
$PN"R21"9;
"IV12D_P21"
$PN"P21"9;
"IV12D_N21"
$PN"N21"9;
"IV12D_M21"
$PN"M21"9;
"IV12D_L21"
$PN"L21"9;
"IV12D_T14"
$PN"T14"9;
"IV12D_R14"
$PN"R14"9;
"IV12D_P14"
$PN"P14"9;
"IV12D_N14"
$PN"N14"9;
"IV12D_M14"
$PN"M14"9;
"IV12D_L14"
$PN"L14"9;
"IV12D_K19"
$PN"K19"9;
"IV12D_K18"
$PN"K18"9;
"IV12D_K17"
$PN"K17"9;
"IV12D_K16"
$PN"K16"9;
"MVDD_CK"
$PN"M6"41;
"MVDD_T6"
$PN"T6"11;
"MVDD_R6"
$PN"R6"11;
"MVDD_P6"
$PN"P6"11;
"MVDD_L6"
$PN"L6"11;
"MVDD_K6"
$PN"K6"11;
"MVDD_J6"
$PN"J6"11;
"MVDD_H6"
$PN"H6"11;
"DP_VCC10A"
$PN"T8"39;
"DP_VCC18A"
$PN"V8"40;
"PE_VCC18A"
$PN"V10"38;
"PE_VCC10A"
$PN"T10"46;
"RC_VCC18A"
$PN"V9"37;
"RC_VCC10A"
$PN"T9"47;
"PLLDVDD_F9"
$PN"F9"36;
"PLLDVDD_E9"
$PN"E9"36;
"DACAV33_W21"
$PN"W21"43;
"PLLAVDD_F7"
$PN"F7"36;
"MVDD_G6"
$PN"G6"11;
"AVDDPLL"
$PN"N5"48;
"IV10D_M8"
$PN"M8"4;
"IV10D_L10"
$PN"L10"4;
"IV10D_L9"
$PN"L9"4;
"ADCREXT1"
$PN"AF18"33;
"ADCVREFN1"
$PN"AD18"49;
"ADCVREFP1"
$PN"AD17"50;
"PLLAHVDD"
$PN"H14"51;
"PLLAVDD_E7"
$PN"E7"36;
"DACRSET"
$PN"AC21"35;
"DACAV33_V21"
$PN"V21"43;
"ADCAV33_Y21"
$PN"Y21"44;
"ADCVREFP0"
$PN"AC20"52;
"ADCVREFN0"
$PN"AB20"53;
"ADCREXT0"
$PN"AF20"42;
%"Q_CAP"
"1","(3750,3200)","0","pure_quanta","I189";
;
TOLERANCE"20%"
MATERIAL"X6S"
VALUE"22UF"
PACK_TYPE"C0603"
VOLTAGE"6.3V"
CDS_LIB"pure_quanta"
PART_NUMBER"CH6221ME900"
LOCATION"C113"
$SEC"1"
CDS_SEC"1";
"B"
$PN"2"24;
"A"
$PN"1"4;
%"Q_CAP"
"1","(3950,1875)","0","pure_quanta","I190";
;
PACK_TYPE"C0603"
VOLTAGE"6.3V"
VALUE"22UF"
TOLERANCE"20%"
MATERIAL"X6S"
PART_NUMBER"CH6221ME900"
CDS_LIB"pure_quanta"
LOCATION"C120"
$SEC"1"
CDS_SEC"1";
"B"
$PN"2"22;
"A"
$PN"1"6;
%"Q_CAP"
"1","(4150,1875)","0","pure_quanta","I191";
;
TOLERANCE"20%"
VALUE"22UF"
VOLTAGE"6.3V"
PACK_TYPE"C0603"
MATERIAL"X6S"
PART_NUMBER"CH6221ME900"
CDS_LIB"pure_quanta"
LOCATION"C125"
$SEC"1"
CDS_SEC"1";
"B"
$PN"2"22;
"A"
$PN"1"6;
%"Q_CAP"
"1","(4625,3825)","0","pure_quanta","I192";
;
VOLTAGE"6.3V"
TOLERANCE"20%"
MATERIAL"X6S"
VALUE"22UF"
PACK_TYPE"C0603"
PART_NUMBER"CH6221ME900"
CDS_LIB"pure_quanta"
LOCATION"C131"
$SEC"1"
CDS_SEC"1";
"B"
$PN"2"25;
"A"
$PN"1"9;
%"Q_CAP"
"1","(4825,3825)","0","pure_quanta","I193";
;
TOLERANCE"20%"
MATERIAL"X6S"
PACK_TYPE"C0603"
VOLTAGE"6.3V"
VALUE"22UF"
PART_NUMBER"CH6221ME900"
CDS_LIB"pure_quanta"
LOCATION"C132"
$SEC"1"
CDS_SEC"1";
"B"
$PN"2"25;
"A"
$PN"1"9;
%"UNIVERSAL_POWER"
"1","(-2150,1050)","0","logical_power","I21";
;
HDL_POWER"P1V2_AUX"
CDS_LIB"logical_power";
"A"10;
%"UNIVERSAL_POWER"
"1","(-2450,1700)","0","logical_power","I22";
;
HDL_POWER"P1V2_AUX"
CDS_LIB"logical_power";
"A"11;
%"Q_CAP"
"1","(-2175,1425)","0","pure_quanta","I23";
;
TOLERANCE"20%"
MATERIAL"X6S"
PART_NUMBER"CH6221ME900"
VALUE"22UF"
PACK_TYPE"C0603"
VOLTAGE"6.3V"
CDS_LIB"pure_quanta"
LOCATION"C55"
$SEC"1"
CDS_SEC"1";
"B"
$PN"2"29;
"A"
$PN"1"11;
%"Q_INDUCTOR"
"1","(-2050,2275)","0","pure_quanta","I24";
;
PART_NUMBER"CX8PG121009"
VALUE"BLM18PG121SN1D/2000MA"
MATERIAL"IND"
PACK_TYPE"SMLF"
CDS_LIB"pure_quanta"
NEEDS_NO_SIZE"TRUE"
LOCATION"L10"
$SEC"1"
CDS_SEC"1";
"1"
$PN"1"13;
"2"
$PN"2"37;
%"UNIVERSAL_POWER"
"1","(-3175,2975)","0","logical_power","I25";
;
HDL_POWER"P1V0_AUX"
CDS_LIB"logical_power";
"A"12;
%"Q_INDUCTOR"
"1","(-2750,2900)","0","pure_quanta","I29";
;
MATERIAL"IND"
PART_NUMBER"CX8PG121009"
VALUE"BLM18PG121SN1D/2000MA"
PACK_TYPE"SMLF"
NEEDS_NO_SIZE"TRUE"
CDS_LIB"pure_quanta"
LOCATION"L8"
$SEC"1"
CDS_SEC"1";
"1"
$PN"1"12;
"2"
$PN"2"36;
%"UNIVERSAL_POWER"
"1","(-2450,2350)","0","logical_power","I30";
;
HDL_POWER"P1V8_AUX"
CDS_LIB"logical_power";
"A"13;
%"Q_CAP"
"1","(-2500,2700)","0","pure_quanta","I31";
;
PACK_TYPE"C0402"
TOLERANCE"10%"
MATERIAL"X6S"
PART_NUMBER"CH5104KEB02"
VALUE"1UF"
VOLTAGE"25V"
CDS_LIB"pure_quanta"
LOCATION"C52"
$SEC"1"
CDS_SEC"1";
"B"
$PN"2"30;
"A"
$PN"1"36;
%"Q_CAP"
"1","(-2300,2700)","0","pure_quanta","I32";
;
PACK_TYPE"0402"
VALUE"0.1UF"
TOLERANCE"10%"
MATERIAL"X7R"
VOLTAGE"25V"
PART_NUMBER"CH4104K1B00"
CDS_LIB"pure_quanta"
LOCATION"C54"
$SEC"1"
CDS_SEC"1";
"B"
$PN"2"30;
"A"
$PN"1"36;
%"Q_CAP"
"1","(-2075,2700)","0","pure_quanta","I33";
;
VALUE"1UF"
VOLTAGE"25V"
PACK_TYPE"C0402"
TOLERANCE"10%"
MATERIAL"X6S"
PART_NUMBER"CH5104KEB02"
CDS_LIB"pure_quanta"
LOCATION"C56"
$SEC"1"
CDS_SEC"1";
"B"
$PN"2"30;
"A"
$PN"1"36;
%"UNIVERSAL_POWER"
"1","(-775,50)","0","logical_power","I44";
;
HDL_POWER"P3V3_P1V8_I2C_I3C"
CDS_LIB"logical_power";
"A"3;
%"Q_CAP"
"1","(-1725,800)","0","pure_quanta","I46";
;
PACK_TYPE"0402"
TOLERANCE"10%"
MATERIAL"X7R"
VOLTAGE"50V"
PART_NUMBER"TMP_QCH22206KB16"
VALUE"2200PF"
CDS_LIB"pure_quanta"
LOCATION"C63"
$SEC"1"
CDS_SEC"1";
"B"
$PN"2"27;
"A"
$PN"1"41;
%"Q_INDUCTOR"
"1","(-1900,1000)","0","pure_quanta","I47";
;
VALUE"BLM18PG121SN1D/2000MA"
MATERIAL"IND"
PART_NUMBER"CX8PG121009"
PACK_TYPE"SMLF"
NEEDS_NO_SIZE"TRUE"
CDS_LIB"pure_quanta"
LOCATION"L11"
$SEC"1"
CDS_SEC"1";
"1"
$PN"1"10;
"2"
$PN"2"41;
%"Q_CAP"
"1","(-1525,800)","0","pure_quanta","I48";
;
PACK_TYPE"C0402"
TOLERANCE"10%"
MATERIAL"X6S"
PART_NUMBER"CH5104KEB02"
VALUE"1UF"
VOLTAGE"25V"
CDS_LIB"pure_quanta"
LOCATION"C67"
$SEC"1"
CDS_SEC"1";
"B"
$PN"2"27;
"A"
$PN"1"41;
%"Q_CAP"
"1","(-1325,800)","0","pure_quanta","I49";
;
VALUE"0.1UF"
VOLTAGE"25V"
TOLERANCE"10%"
MATERIAL"X7R"
PACK_TYPE"0402"
PART_NUMBER"CH4104K1B00"
CDS_LIB"pure_quanta"
LOCATION"C71"
$SEC"1"
CDS_SEC"1";
"B"
$PN"2"27;
"A"
$PN"1"41;
%"UNIVERSAL_GND"
"1","(-1225,525)","0","logical_power","I50";
;
HDL_POWER"GND"
CDS_LIB"logical_power";
"A"27;
%"Q_CAP"
"1","(-1125,800)","0","pure_quanta","I51";
;
PACK_TYPE"0402"
VALUE"0.1UF"
TOLERANCE"10%"
MATERIAL"X7R"
PART_NUMBER"CH4104K1B00"
VOLTAGE"25V"
CDS_LIB"pure_quanta"
LOCATION"C73"
$SEC"1"
CDS_SEC"1";
"B"
$PN"2"27;
"A"
$PN"1"41;
%"Q_CAP"
"1","(-1975,1425)","0","pure_quanta","I52";
;
PACK_TYPE"C0402"
TOLERANCE"10%"
MATERIAL"X6S"
VALUE"1UF"
VOLTAGE"25V"
PART_NUMBER"CH5104KEB02"
CDS_LIB"pure_quanta"
LOCATION"C58"
$SEC"1"
CDS_SEC"1";
"B"
$PN"2"29;
"A"
$PN"1"11;
%"Q_CAP"
"1","(-1775,1425)","0","pure_quanta","I53";
;
PACK_TYPE"C0402"
TOLERANCE"10%"
MATERIAL"X6S"
PART_NUMBER"CH5104KEB02"
VALUE"1UF"
VOLTAGE"25V"
CDS_LIB"pure_quanta"
LOCATION"C62"
$SEC"1"
CDS_SEC"1";
"B"
$PN"2"29;
"A"
$PN"1"11;
%"Q_CAP"
"1","(-1575,1425)","0","pure_quanta","I54";
;
VALUE"0.1UF"
VOLTAGE"25V"
TOLERANCE"10%"
MATERIAL"X7R"
PACK_TYPE"0402"
PART_NUMBER"CH4104K1B00"
CDS_LIB"pure_quanta"
LOCATION"C66"
$SEC"1"
CDS_SEC"1";
"B"
$PN"2"29;
"A"
$PN"1"11;
%"Q_CAP"
"1","(-1825,2075)","0","pure_quanta","I55";
;
TOLERANCE"10%"
MATERIAL"X6S"
VALUE"1UF"
VOLTAGE"25V"
PACK_TYPE"C0402"
PART_NUMBER"CH5104KEB02"
CDS_LIB"pure_quanta"
LOCATION"C61"
$SEC"1"
CDS_SEC"1";
"B"
$PN"2"28;
"A"
$PN"1"37;
%"UNIVERSAL_GND"
"1","(-1625,1775)","0","logical_power","I56";
;
HDL_POWER"GND"
CDS_LIB"logical_power";
"A"28;
%"Q_CAP"
"1","(-1375,1425)","0","pure_quanta","I57";
;
PACK_TYPE"0402"
VALUE"0.1UF"
TOLERANCE"10%"
MATERIAL"X7R"
VOLTAGE"25V"
PART_NUMBER"CH4104K1B00"
CDS_LIB"pure_quanta"
LOCATION"C70"
$SEC"1"
CDS_SEC"1";
"B"
$PN"2"29;
"A"
$PN"1"11;
%"Q_CAP"
"1","(-1175,1425)","0","pure_quanta","I58";
;
PACK_TYPE"0402"
VALUE"0.1UF"
TOLERANCE"10%"
MATERIAL"X7R"
VOLTAGE"25V"
PART_NUMBER"CH4104K1B00"
CDS_LIB"pure_quanta"
LOCATION"C72"
$SEC"1"
CDS_SEC"1";
"B"
$PN"2"29;
"A"
$PN"1"11;
%"Q_CAP"
"1","(-1400,2075)","0","pure_quanta","I59";
;
PACK_TYPE"0402"
VALUE"0.1UF"
TOLERANCE"10%"
MATERIAL"X7R"
PART_NUMBER"CH4104K1B00"
VOLTAGE"25V"
CDS_LIB"pure_quanta"
LOCATION"C69"
$SEC"1"
CDS_SEC"1";
"B"
$PN"2"28;
"A"
$PN"1"37;
%"UNIVERSAL_POWER"
"1","(-600,275)","0","logical_power","I60";
;
HDL_POWER"P3V3_P1V8_SD2VDD"
CDS_LIB"logical_power";
"A"14;
%"UNIVERSAL_POWER"
"1","(-600,700)","0","logical_power","I61";
;
HDL_POWER"P3V3_P2V5_P1V8_RVDD"
CDS_LIB"logical_power";
"A"15;
%"UNIVERSAL_GND"
"1","(-875,1150)","0","logical_power","I62";
;
HDL_POWER"GND"
CDS_LIB"logical_power";
"A"29;
%"UNIVERSAL_POWER"
"1","(-475,450)","0","logical_power","I63";
;
HDL_POWER"P3V3_P1V8_SD1VDD"
CDS_LIB"logical_power";
"A"16;
%"UNIVERSAL_POWER"
"1","(-450,900)","0","logical_power","I64";
;
HDL_POWER"P1V2_P1V0_I3C_VDDL2"
CDS_LIB"logical_power";
"A"17;
%"UNIVERSAL_POWER"
"1","(-375,1100)","0","logical_power","I65";
;
HDL_POWER"P1V2_P1V0_I3C_VDDL1"
CDS_LIB"logical_power";
"A"18;
%"Q_CAP"
"1","(-975,1425)","0","pure_quanta","I66";
;
PACK_TYPE"0402"
VALUE"0.1UF"
TOLERANCE"10%"
MATERIAL"X7R"
VOLTAGE"25V"
PART_NUMBER"CH4104K1B00"
CDS_LIB"pure_quanta"
LOCATION"C74"
$SEC"1"
CDS_SEC"1";
"B"
$PN"2"29;
"A"
$PN"1"11;
%"Q_CAP"
"1","(-1875,2700)","0","pure_quanta","I79";
;
VALUE"0.1UF"
TOLERANCE"10%"
MATERIAL"X7R"
VOLTAGE"25V"
PACK_TYPE"0402"
PART_NUMBER"CH4104K1B00"
CDS_LIB"pure_quanta"
LOCATION"C59"
$SEC"1"
CDS_SEC"1";
"B"
$PN"2"30;
"A"
$PN"1"36;
%"UNIVERSAL_GND"
"1","(-1600,2425)","0","logical_power","I80";
;
HDL_POWER"GND"
CDS_LIB"logical_power";
"A"30;
%"Q_CAP"
"1","(-1700,2700)","0","pure_quanta","I81";
;
TOLERANCE"10%"
MATERIAL"X6S"
VALUE"1UF"
VOLTAGE"25V"
PACK_TYPE"C0402"
PART_NUMBER"CH5104KEB02"
CDS_LIB"pure_quanta"
LOCATION"C64"
$SEC"1"
CDS_SEC"1";
"B"
$PN"2"30;
"A"
$PN"1"36;
%"Q_CAP"
"1","(-1500,2700)","0","pure_quanta","I82";
;
PART_NUMBER"CH4104K1B00"
TOLERANCE"10%"
VOLTAGE"25V"
VALUE"0.1UF"
MATERIAL"X7R"
PACK_TYPE"0402"
CDS_LIB"pure_quanta"
LOCATION"C68"
$SEC"1"
CDS_SEC"1";
"B"
$PN"2"30;
"A"
$PN"1"36;
%"UNIVERSAL_GND"
"1","(-1750,3125)","0","logical_power","I83";
;
HDL_POWER"GND"
CDS_LIB"logical_power";
"A"31;
%"Q_RES"
"1","(-1450,3600)","0","pure_quanta","I86";
;
PART_NUMBER"CS34992FB05"
MATERIAL"CHIP"
VALUE"49.9K"
PACK_TYPE"0402LF"
WATTAGE"1/16W"
TOLERANCE"1%"
CDS_LIB"pure_quanta"
LOCATION"R234"
$SEC"1"
CDS_SEC"1";
"B"
$PN"2"33;
"A"
$PN"1"31;
%"Q_RES"
"1","(-1450,3850)","0","pure_quanta","I87";
;
PART_NUMBER"CS34992FB05"
VALUE"49.9K"
MATERIAL"CHIP"
PACK_TYPE"0402LF"
WATTAGE"1/16W"
TOLERANCE"1%"
CDS_LIB"pure_quanta"
LOCATION"R233"
$SEC"1"
CDS_SEC"1";
"B"
$PN"2"42;
"A"
$PN"1"31;
%"Q_CAP"
"1","(-900,4400)","0","pure_quanta","I93";
;
PART_NUMBER"CH5104KEB02"
PACK_TYPE"C0402"
MATERIAL"X6S"
TOLERANCE"10%"
VOLTAGE"25V"
VALUE"1UF"
CDS_LIB"pure_quanta"
LOCATION"C75"
$SEC"1"
CDS_SEC"1";
"B"
$PN"2"32;
"A"
$PN"1"44;
%"UNIVERSAL_GND"
"1","(-675,4075)","0","logical_power","I96";
;
HDL_POWER"GND"
CDS_LIB"logical_power";
"A"32;
%"UNIVERSAL_POWER"
"1","(-1400,4675)","0","logical_power","I98";
;
HDL_POWER"P3V3_AUX"
CDS_LIB"logical_power";
"A"19;
%"Q_INDUCTOR"
"1","(-1100,4625)","0","pure_quanta","I99";
;
MATERIAL"IND"
PART_NUMBER"CX8PG121009"
VALUE"BLM18PG121SN1D/2000MA"
PACK_TYPE"SMLF"
NEEDS_NO_SIZE"TRUE"
CDS_LIB"pure_quanta"
LOCATION"L12"
$SEC"1"
CDS_SEC"1";
"1"
$PN"1"19;
"2"
$PN"2"44;
END.
